# TIMECARD (Time Appliance Project (Time Card)) — schematic netlist excerpt (pin names and nets, part order shuffled) for the footprints in the layout excerpt that follows; sources: Cadence DE-HDL packaged netlist, KiCad conversion of R4006-B0001-02_R01.brd

R370  RESISTOR  49.9OHM 1%  pkg SMC_0402R_H016  page 23 : \1\ = BF_ANT4_IN ; \2\ = ANT4_IN
TP201  TP_PIONT  pkg TP010CT020B030_PTH  page 25 : \1\ = IO_L22P_35
SP66  NULL  pkg DUMMY  page 34

(kicad_pcb
	(version 20260206)
	(generator "pcbnew")
	(generator_version "10.0")
	(general
		(thickness 1.6)
		(legacy_teardrops no)
	)
	(paper "A4")
	(title_block
		(title "timecard-production-celestica-r4006 — R4006-B0001-02_R01.brd")
		(comment 1 "Time Appliance Project (Time Card) / footprints 381-383 of 1113")
	)
	(layers
		(0 "F.Cu" signal "TOP")
		(4 "In1.Cu" signal "L02_GND1")
		(6 "In2.Cu" signal "L03_SIG1")
		(8 "In3.Cu" signal "L04_GND2")
		(10 "In4.Cu" signal "L05_VCC1")
		(12 "In5.Cu" signal "L06_VCC2")
		(14 "In6.Cu" signal "L07_GND3")
		(16 "In7.Cu" signal "L08_SIG2")
		(18 "In8.Cu" signal "L09_GND4")
		(2 "B.Cu" signal "BOTTOM")
		(9 "F.Adhes" user "F.Adhesive")
		(11 "B.Adhes" user "B.Adhesive")
		(13 "F.Paste" user "Package Geometry/Pastemask Top")
		(15 "B.Paste" user "Package Geometry/Pastemask Bottom")
		(5 "F.SilkS" user "Ref Des/Silkscreen Top")
		(7 "B.SilkS" user "Ref Des/Silkscreen Bottom")
		(1 "F.Mask" user "Board Geometry/Soldermask Top")
		(3 "B.Mask" user "Board Geometry/Soldermask Bottom")
		(17 "Dwgs.User" user "User.Drawings")
		(19 "Cmts.User" user "User.Comments")
		(21 "Eco1.User" user "User.Eco1")
		(23 "Eco2.User" user "User.Eco2")
		(25 "Edge.Cuts" user "Board Geometry/Outline")
		(27 "Margin" user)
		(31 "F.CrtYd" user "Package Geometry/Place Bound Top")
		(29 "B.CrtYd" user "Package Geometry/Place Bound Bottom")
		(35 "F.Fab" user "Ref Des/Assembly Top")
		(33 "B.Fab" user "Ref Des/Assembly Bottom")
	)
	(footprint ""
		(layer "F.Cu")
		(at 12.319 -22.987 90)
		(property "Reference" "R370"
			(at -0.635 -3.26263 90)
			(unlocked yes)
			(layer "F.SilkS")
			(effects
				(font
					(size 0.7874 0.5842)
					(thickness 0.1524)
				)
			)
		)
		(property "Value" "VAL*"
			(at 0.02032 2.13233 90)
			(unlocked yes)
			(layer "F.Fab")
			(hide yes)
			(effects
				(font
					(size 0.7874 0.5842)
					(thickness 0.1524)
				)
			)
		)
		(property "Tolerance" "TOL*"
			(at 0.044704 3.05435 90)
			(unlocked yes)
			(layer "Cmts.User")
			(hide yes)
			(effects
				(font
					(size 0.7874 0.5842)
					(thickness 0.1524)
				)
			)
		)
		(property "User Part Number" "PARTNUM*"
			(at 0.02032 4.024884 90)
			(unlocked yes)
			(layer "Cmts.User")
			(hide yes)
			(effects
				(font
					(size 0.7874 0.5842)
					(thickness 0.1524)
				)
			)
		)
		(property "Device Type" "RESISTOR-G155-149R9-01,49.9OHMA"
			(at 0.008382 1.210564 90)
			(unlocked yes)
			(layer "F.Fab")
			(hide yes)
			(effects
				(font
					(size 0.7874 0.5842)
					(thickness 0.1524)
				)
			)
		)
		(duplicate_pad_numbers_are_jumpers no)
		(fp_line
			(start 1.143 -0.5588)
			(end -1.143 -0.5588)
			(stroke
				(width 0.1)
				(type default)
			)
			(layer "F.SilkS")
		)
		(fp_line
			(start -1.143 -0.5588)
			(end -1.143 0.5588)
			(stroke
				(width 0.1)
				(type default)
			)
			(layer "F.SilkS")
		)
		(fp_line
			(start 1.143 0.5588)
			(end 1.143 -0.5588)
			(stroke
				(width 0.1)
				(type default)
			)
			(layer "F.SilkS")
		)
		(fp_line
			(start -1.143 0.5588)
			(end 1.143 0.5588)
			(stroke
				(width 0.1)
				(type default)
			)
			(layer "F.SilkS")
		)
		(fp_poly
			(pts
				(xy -1.143 0.5588) (xy 1.143 0.5588) (xy 1.143 -0.5588) (xy -1.143 -0.5588)
			)
			(stroke
				(width 0)
				(type default)
			)
			(fill no)
			(layer "F.CrtYd")
		)
		(fp_line
			(start 0.508 -0.3048)
			(end -0.508 -0.3048)
			(stroke
				(width 0.1)
				(type default)
			)
			(layer "F.Fab")
		)
		(fp_line
			(start -0.508 -0.3048)
			(end -0.508 0.3048)
			(stroke
				(width 0.1)
				(type default)
			)
			(layer "F.Fab")
		)
		(fp_line
			(start 0.508 0.3048)
			(end 0.508 -0.3048)
			(stroke
				(width 0.1)
				(type default)
			)
			(layer "F.Fab")
		)
		(fp_line
			(start -0.508 0.3048)
			(end 0.508 0.3048)
			(stroke
				(width 0.1)
				(type default)
			)
			(layer "F.Fab")
		)
		(pad "1" smd rect
			(at -0.5334 0 90)
			(size 0.7112 0.6096)
			(layers "F.Cu" "F.Mask" "F.Paste")
			(net "BF_ANT4_IN")
		)
		(pad "2" smd rect
			(at 0.5334 0 90)
			(size 0.7112 0.6096)
			(layers "F.Cu" "F.Mask" "F.Paste")
			(net "ANT4_IN")
		)
		(zone
			(layer "F.Cu")
			(hatch none 0.5)
			(connect_pads
				(clearance 0)
			)
			(min_thickness 0.25)
			(keepout
				(tracks allowed)
				(vias not_allowed)
				(pads allowed)
				(copperpour not_allowed)
				(footprints allowed)
			)
			(placement
				(enabled no)
				(sheetname "")
			)
			(fill
				(thermal_gap 0.5)
				(thermal_bridge_width 0.5)
				(island_removal_mode 0)
			)
			(polygon
				(pts
					(xy 12.6238 -22.9108) (xy 12.6238 -23.0632) (xy 12.0142 -23.0632) (xy 12.0142 -22.9108)
				)
			)
		)
		(zone
			(layer "F.Cu")
			(hatch none 0.5)
			(connect_pads
				(clearance 0)
			)
			(min_thickness 0.25)
			(keepout
				(tracks not_allowed)
				(vias allowed)
				(pads allowed)
				(copperpour not_allowed)
				(footprints allowed)
			)
			(placement
				(enabled no)
				(sheetname "")
			)
			(fill
				(thermal_gap 0.5)
				(thermal_bridge_width 0.5)
				(island_removal_mode 0)
			)
			(polygon
				(pts
					(xy 12.6238 -22.9108) (xy 12.6238 -23.0632) (xy 12.0142 -23.0632) (xy 12.0142 -22.9108)
				)
			)
		)
	)
	(footprint ""
		(layer "F.Cu")
		(at 46.482 -127.127)
		(property "Reference" "SP66"
			(at 0 0 0)
			(layer "F.SilkS")
			(hide yes)
			(effects
				(font
					(size 1.27 1.27)
				)
			)
		)
		(property "Value" ""
			(at 0 0 0)
			(layer "F.Fab")
			(effects
				(font
					(size 1.27 1.27)
				)
			)
		)
		(duplicate_pad_numbers_are_jumpers no)
	)
	(footprint ""
		(layer "F.Cu")
		(at 122.3264 -31.9532 90)
		(property "Reference" "TP201"
			(at -1.50495 -0.3302 0)
			(unlocked yes)
			(layer "F.SilkS")
			(effects
				(font
					(size 0.635 0.4064)
					(thickness 0.1524)
				)
				(justify left)
			)
		)
		(property "Value" ""
			(at 0 0 90)
			(layer "F.Fab")
			(effects
				(font
					(size 1.27 1.27)
				)
			)
		)
		(property "Device Type" "TP_PIONT-TP010CT020B030_PTH-TPA"
			(at -1.341882 0.996696 90)
			(unlocked yes)
			(layer "F.Fab")
			(hide yes)
			(effects
				(font
					(size 0.7874 0.5842)
					(thickness 0.1524)
				)
				(justify left)
			)
		)
		(duplicate_pad_numbers_are_jumpers no)
		(fp_poly
			(pts
				(arc
					(start 0 0.889)
					(mid 0 -0.889)
					(end 0 0.889)
				)
			)
			(stroke
				(width 0)
				(type default)
			)
			(fill no)
			(layer "B.CrtYd")
		)
		(fp_poly
			(pts
				(arc
					(start 0 0.889)
					(mid 0 -0.889)
					(end 0 0.889)
				)
			)
			(stroke
				(width 0)
				(type default)
			)
			(fill no)
			(layer "F.CrtYd")
		)
		(pad "1" thru_hole circle
			(at 0 0 90)
			(size 0.508 0.508)
			(drill 0.254)
			(layers "*.Cu" "*.Mask")
			(remove_unused_layers no)
			(net "IO_L22P_35")
			(clearance 0.1016)
			(padstack
				(mode front_inner_back)
				(layer "Inner"
					(shape circle)
					(size 0.508 0.508)
					(clearance 0.1016)
				)
				(layer "B.Cu"
					(shape circle)
					(size 0.762 0.762)
					(clearance -0.0254)
				)
			)
		)
	)
)
